(kicad_pcb
	(version 20260206)
	(generator "pcbnew")
	(generator_version "10.0")
	(general
		(thickness 1.6)
		(legacy_teardrops no)
	)
	(paper "A4")
	(title_block
		(title "12092022_DA0F0TMDCD0_F0T_Management_Board_D_brd_V3_OCP.brd")
		(comment 1 "Grand Teton / footprints 594-598 of 1440")
	)
	(layers
		(0 "F.Cu" signal "TOP")
		(4 "In1.Cu" signal "GND")
		(6 "In2.Cu" signal "IN1")
		(8 "In3.Cu" signal "GND1")
		(10 "In4.Cu" signal "IN2")
		(12 "In5.Cu" signal "VCC")
		(14 "In6.Cu" signal "VCC1")
		(16 "In7.Cu" signal "IN3")
		(18 "In8.Cu" signal "GND2")
		(20 "In9.Cu" signal "IN4")
		(22 "In10.Cu" signal "GND3")
		(2 "B.Cu" signal "BOTTOM")
		(9 "F.Adhes" user "F.Adhesive")
		(11 "B.Adhes" user "B.Adhesive")
		(13 "F.Paste" user "Package Geometry/Pastemask Top")
		(15 "B.Paste" user "Package Geometry/Pastemask Bottom")
		(5 "F.SilkS" user "Ref Des/Silkscreen Top")
		(7 "B.SilkS" user "Ref Des/Silkscreen Bottom")
		(1 "F.Mask" user "Board Geometry/Soldermask Top")
		(3 "B.Mask" user "Board Geometry/Soldermask Bottom")
		(17 "Dwgs.User" user "User.Drawings")
		(19 "Cmts.User" user "User.Comments")
		(21 "Eco1.User" user "User.Eco1")
		(23 "Eco2.User" user "User.Eco2")
		(25 "Edge.Cuts" user "Board Geometry/Outline")
		(27 "Margin" user)
		(31 "F.CrtYd" user "Package Geometry/Place Bound Top")
		(29 "B.CrtYd" user "Package Geometry/Place Bound Bottom")
		(35 "F.Fab" user "Ref Des/Assembly Top")
		(33 "B.Fab" user "Ref Des/Assembly Bottom")
	)
	(footprint ""
		(layer "F.Cu")
		(at 77.343 -20.193 180)
		(property "Reference" "R284"
			(at 0 0 180)
			(layer "F.SilkS")
			(hide yes)
			(effects
				(font
					(size 1.27 1.27)
				)
			)
		)
		(property "Value" ""
			(at 0 0 180)
			(layer "F.Fab")
			(effects
				(font
					(size 1.27 1.27)
				)
			)
		)
		(duplicate_pad_numbers_are_jumpers no)
		(fp_line
			(start 0.7874 0.4064)
			(end -0.7874 0.4064)
			(stroke
				(width 0.1524)
				(type default)
			)
			(layer "F.SilkS")
		)
		(fp_line
			(start 0.7874 -0.4064)
			(end 0.7874 0.4064)
			(stroke
				(width 0.1524)
				(type default)
			)
			(layer "F.SilkS")
		)
		(fp_line
			(start -0.7874 0.4064)
			(end -0.7874 -0.4064)
			(stroke
				(width 0.1524)
				(type default)
			)
			(layer "F.SilkS")
		)
		(fp_line
			(start -0.7874 -0.4064)
			(end 0.7874 -0.4064)
			(stroke
				(width 0.1524)
				(type default)
			)
			(layer "F.SilkS")
		)
		(fp_line
			(start 0.67945 0.3048)
			(end 0.120396 0.3048)
			(stroke
				(width 0.1)
				(type default)
			)
			(layer "F.Fab")
		)
		(fp_line
			(start 0.67945 -0.3048)
			(end 0.67945 0.3048)
			(stroke
				(width 0.1)
				(type default)
			)
			(layer "F.Fab")
		)
		(fp_line
			(start 0.12065 -0.2794)
			(end 0.12065 -0.3048)
			(stroke
				(width 0.1)
				(type default)
			)
			(layer "F.Fab")
		)
		(fp_line
			(start 0.12065 -0.3048)
			(end 0.67945 -0.3048)
			(stroke
				(width 0.1)
				(type default)
			)
			(layer "F.Fab")
		)
		(fp_line
			(start 0.120396 0.3048)
			(end 0.120396 0.2794)
			(stroke
				(width 0.1)
				(type default)
			)
			(layer "F.Fab")
		)
		(fp_line
			(start 0.120396 0.2794)
			(end -0.12065 0.2794)
			(stroke
				(width 0.1)
				(type default)
			)
			(layer "F.Fab")
		)
		(fp_line
			(start -0.12065 0.3048)
			(end -0.67945 0.3048)
			(stroke
				(width 0.1)
				(type default)
			)
			(layer "F.Fab")
		)
		(fp_line
			(start -0.12065 0.2794)
			(end -0.12065 0.3048)
			(stroke
				(width 0.1)
				(type default)
			)
			(layer "F.Fab")
		)
		(fp_line
			(start -0.12065 -0.2794)
			(end 0.12065 -0.2794)
			(stroke
				(width 0.1)
				(type default)
			)
			(layer "F.Fab")
		)
		(fp_line
			(start -0.12065 -0.305054)
			(end -0.12065 -0.2794)
			(stroke
				(width 0.1)
				(type default)
			)
			(layer "F.Fab")
		)
		(fp_line
			(start -0.67945 0.3048)
			(end -0.67945 -0.305054)
			(stroke
				(width 0.1)
				(type default)
			)
			(layer "F.Fab")
		)
		(fp_line
			(start -0.67945 -0.305054)
			(end -0.12065 -0.305054)
			(stroke
				(width 0.1)
				(type default)
			)
			(layer "F.Fab")
		)
		(pad "1" smd circle
			(at -0.40005 0 180)
			(size 0 0)
			(layers "F.Cu" "F.Mask" "F.Paste")
			(net "FM_UARTSW_MSB_N")
		)
		(pad "2" smd circle
			(at 0.40005 0 180)
			(size 0 0)
			(layers "F.Cu" "F.Mask" "F.Paste")
			(net "FM_UARTSW_MSB_R1_N")
		)
	)
	(footprint ""
		(layer "F.Cu")
		(at 20.066 -102.743 90)
		(property "Reference" "R323"
			(at 0 0 90)
			(layer "F.SilkS")
			(hide yes)
			(effects
				(font
					(size 1.27 1.27)
				)
			)
		)
		(property "Value" ""
			(at 0 0 90)
			(layer "F.Fab")
			(effects
				(font
					(size 1.27 1.27)
				)
			)
		)
		(duplicate_pad_numbers_are_jumpers no)
		(fp_line
			(start 0.7874 -0.4064)
			(end 0.7874 0.4064)
			(stroke
				(width 0.1524)
				(type default)
			)
			(layer "F.SilkS")
		)
		(fp_line
			(start -0.7874 -0.4064)
			(end 0.7874 -0.4064)
			(stroke
				(width 0.1524)
				(type default)
			)
			(layer "F.SilkS")
		)
		(fp_line
			(start 0.7874 0.4064)
			(end -0.7874 0.4064)
			(stroke
				(width 0.1524)
				(type default)
			)
			(layer "F.SilkS")
		)
		(fp_line
			(start -0.7874 0.4064)
			(end -0.7874 -0.4064)
			(stroke
				(width 0.1524)
				(type default)
			)
			(layer "F.SilkS")
		)
		(fp_line
			(start -0.12065 -0.305054)
			(end -0.12065 -0.2794)
			(stroke
				(width 0.1)
				(type default)
			)
			(layer "F.Fab")
		)
		(fp_line
			(start -0.67945 -0.305054)
			(end -0.12065 -0.305054)
			(stroke
				(width 0.1)
				(type default)
			)
			(layer "F.Fab")
		)
		(fp_line
			(start 0.67945 -0.3048)
			(end 0.67945 0.3048)
			(stroke
				(width 0.1)
				(type default)
			)
			(layer "F.Fab")
		)
		(fp_line
			(start 0.12065 -0.3048)
			(end 0.67945 -0.3048)
			(stroke
				(width 0.1)
				(type default)
			)
			(layer "F.Fab")
		)
		(fp_line
			(start 0.12065 -0.2794)
			(end 0.12065 -0.3048)
			(stroke
				(width 0.1)
				(type default)
			)
			(layer "F.Fab")
		)
		(fp_line
			(start -0.12065 -0.2794)
			(end 0.12065 -0.2794)
			(stroke
				(width 0.1)
				(type default)
			)
			(layer "F.Fab")
		)
		(fp_line
			(start 0.120396 0.2794)
			(end -0.12065 0.2794)
			(stroke
				(width 0.1)
				(type default)
			)
			(layer "F.Fab")
		)
		(fp_line
			(start -0.12065 0.2794)
			(end -0.12065 0.3048)
			(stroke
				(width 0.1)
				(type default)
			)
			(layer "F.Fab")
		)
		(fp_line
			(start 0.67945 0.3048)
			(end 0.120396 0.3048)
			(stroke
				(width 0.1)
				(type default)
			)
			(layer "F.Fab")
		)
		(fp_line
			(start 0.120396 0.3048)
			(end 0.120396 0.2794)
			(stroke
				(width 0.1)
				(type default)
			)
			(layer "F.Fab")
		)
		(fp_line
			(start -0.12065 0.3048)
			(end -0.67945 0.3048)
			(stroke
				(width 0.1)
				(type default)
			)
			(layer "F.Fab")
		)
		(fp_line
			(start -0.67945 0.3048)
			(end -0.67945 -0.305054)
			(stroke
				(width 0.1)
				(type default)
			)
			(layer "F.Fab")
		)
		(pad "1" smd circle
			(at -0.40005 0 90)
			(size 0 0)
			(layers "F.Cu" "F.Mask" "F.Paste")
			(net "PWRGD_P1V2_AUX_R1")
		)
		(pad "2" smd circle
			(at 0.40005 0 90)
			(size 0 0)
			(layers "F.Cu" "F.Mask" "F.Paste")
			(net "PWRGD_P1V2_AUX")
		)
	)
	(footprint ""
		(layer "F.Cu")
		(at 11.761978 -52.008532 90)
		(property "Reference" "PC205"
			(at 0 0 90)
			(layer "F.SilkS")
			(hide yes)
			(effects
				(font
					(size 1.27 1.27)
				)
			)
		)
		(property "Value" ""
			(at 0 0 90)
			(layer "F.Fab")
			(effects
				(font
					(size 1.27 1.27)
				)
			)
		)
		(duplicate_pad_numbers_are_jumpers no)
		(fp_line
			(start 0.7874 -0.4064)
			(end 0.7874 0.4064)
			(stroke
				(width 0.1524)
				(type default)
			)
			(layer "F.SilkS")
		)
		(fp_line
			(start -0.7874 -0.4064)
			(end 0.7874 -0.4064)
			(stroke
				(width 0.1524)
				(type default)
			)
			(layer "F.SilkS")
		)
		(fp_line
			(start 0.7874 0.4064)
			(end -0.7874 0.4064)
			(stroke
				(width 0.1524)
				(type default)
			)
			(layer "F.SilkS")
		)
		(fp_line
			(start -0.7874 0.4064)
			(end -0.7874 -0.4064)
			(stroke
				(width 0.1524)
				(type default)
			)
			(layer "F.SilkS")
		)
		(fp_line
			(start -0.12065 -0.305054)
			(end -0.12065 -0.2794)
			(stroke
				(width 0.1)
				(type default)
			)
			(layer "F.Fab")
		)
		(fp_line
			(start -0.67945 -0.305054)
			(end -0.12065 -0.305054)
			(stroke
				(width 0.1)
				(type default)
			)
			(layer "F.Fab")
		)
		(fp_line
			(start 0.67945 -0.3048)
			(end 0.67945 0.3048)
			(stroke
				(width 0.1)
				(type default)
			)
			(layer "F.Fab")
		)
		(fp_line
			(start 0.12065 -0.3048)
			(end 0.67945 -0.3048)
			(stroke
				(width 0.1)
				(type default)
			)
			(layer "F.Fab")
		)
		(fp_line
			(start 0.12065 -0.2794)
			(end 0.12065 -0.3048)
			(stroke
				(width 0.1)
				(type default)
			)
			(layer "F.Fab")
		)
		(fp_line
			(start -0.12065 -0.2794)
			(end 0.12065 -0.2794)
			(stroke
				(width 0.1)
				(type default)
			)
			(layer "F.Fab")
		)
		(fp_line
			(start 0.120396 0.2794)
			(end -0.12065 0.2794)
			(stroke
				(width 0.1)
				(type default)
			)
			(layer "F.Fab")
		)
		(fp_line
			(start -0.12065 0.2794)
			(end -0.12065 0.3048)
			(stroke
				(width 0.1)
				(type default)
			)
			(layer "F.Fab")
		)
		(fp_line
			(start 0.67945 0.3048)
			(end 0.120396 0.3048)
			(stroke
				(width 0.1)
				(type default)
			)
			(layer "F.Fab")
		)
		(fp_line
			(start 0.120396 0.3048)
			(end 0.120396 0.2794)
			(stroke
				(width 0.1)
				(type default)
			)
			(layer "F.Fab")
		)
		(fp_line
			(start -0.12065 0.3048)
			(end -0.67945 0.3048)
			(stroke
				(width 0.1)
				(type default)
			)
			(layer "F.Fab")
		)
		(fp_line
			(start -0.67945 0.3048)
			(end -0.67945 -0.305054)
			(stroke
				(width 0.1)
				(type default)
			)
			(layer "F.Fab")
		)
		(pad "1" smd circle
			(at -0.40005 0 90)
			(size 0 0)
			(layers "F.Cu" "F.Mask" "F.Paste")
			(net "EN_P5V_AUX")
		)
		(pad "2" smd circle
			(at 0.40005 0 90)
			(size 0 0)
			(layers "F.Cu" "F.Mask" "F.Paste")
			(net "GND")
		)
	)
	(footprint ""
		(layer "F.Cu")
		(at 12.799568 -50.110898 -90)
		(property "Reference" "PC272"
			(at 0 0 270)
			(layer "F.SilkS")
			(hide yes)
			(effects
				(font
					(size 1.27 1.27)
				)
			)
		)
		(property "Value" ""
			(at 0 0 270)
			(layer "F.Fab")
			(effects
				(font
					(size 1.27 1.27)
				)
			)
		)
		(duplicate_pad_numbers_are_jumpers no)
		(fp_line
			(start -0.7874 0.4064)
			(end -0.7874 -0.4064)
			(stroke
				(width 0.1524)
				(type default)
			)
			(layer "F.SilkS")
		)
		(fp_line
			(start 0.7874 0.4064)
			(end -0.7874 0.4064)
			(stroke
				(width 0.1524)
				(type default)
			)
			(layer "F.SilkS")
		)
		(fp_line
			(start -0.7874 -0.4064)
			(end 0.7874 -0.4064)
			(stroke
				(width 0.1524)
				(type default)
			)
			(layer "F.SilkS")
		)
		(fp_line
			(start 0.7874 -0.4064)
			(end 0.7874 0.4064)
			(stroke
				(width 0.1524)
				(type default)
			)
			(layer "F.SilkS")
		)
		(fp_line
			(start -0.67945 0.3048)
			(end -0.67945 -0.305054)
			(stroke
				(width 0.1)
				(type default)
			)
			(layer "F.Fab")
		)
		(fp_line
			(start -0.12065 0.3048)
			(end -0.67945 0.3048)
			(stroke
				(width 0.1)
				(type default)
			)
			(layer "F.Fab")
		)
		(fp_line
			(start 0.120396 0.3048)
			(end 0.120396 0.2794)
			(stroke
				(width 0.1)
				(type default)
			)
			(layer "F.Fab")
		)
		(fp_line
			(start 0.67945 0.3048)
			(end 0.120396 0.3048)
			(stroke
				(width 0.1)
				(type default)
			)
			(layer "F.Fab")
		)
		(fp_line
			(start -0.12065 0.2794)
			(end -0.12065 0.3048)
			(stroke
				(width 0.1)
				(type default)
			)
			(layer "F.Fab")
		)
		(fp_line
			(start 0.120396 0.2794)
			(end -0.12065 0.2794)
			(stroke
				(width 0.1)
				(type default)
			)
			(layer "F.Fab")
		)
		(fp_line
			(start -0.12065 -0.2794)
			(end 0.12065 -0.2794)
			(stroke
				(width 0.1)
				(type default)
			)
			(layer "F.Fab")
		)
		(fp_line
			(start 0.12065 -0.2794)
			(end 0.12065 -0.3048)
			(stroke
				(width 0.1)
				(type default)
			)
			(layer "F.Fab")
		)
		(fp_line
			(start 0.12065 -0.3048)
			(end 0.67945 -0.3048)
			(stroke
				(width 0.1)
				(type default)
			)
			(layer "F.Fab")
		)
		(fp_line
			(start 0.67945 -0.3048)
			(end 0.67945 0.3048)
			(stroke
				(width 0.1)
				(type default)
			)
			(layer "F.Fab")
		)
		(fp_line
			(start -0.67945 -0.305054)
			(end -0.12065 -0.305054)
			(stroke
				(width 0.1)
				(type default)
			)
			(layer "F.Fab")
		)
		(fp_line
			(start -0.12065 -0.305054)
			(end -0.12065 -0.2794)
			(stroke
				(width 0.1)
				(type default)
			)
			(layer "F.Fab")
		)
		(pad "1" smd circle
			(at -0.40005 0 270)
			(size 0 0)
			(layers "F.Cu" "F.Mask" "F.Paste")
			(net "P5V_AUX_FB")
		)
		(pad "2" smd circle
			(at 0.40005 0 270)
			(size 0 0)
			(layers "F.Cu" "F.Mask" "F.Paste")
			(net "P5V_AUX")
		)
	)
	(footprint ""
		(layer "F.Cu")
		(at 39.500302 -97.910142 90)
		(property "Reference" "U17"
			(at 1.861058 9.345168 90)
			(unlocked yes)
			(layer "F.SilkS")
			(effects
				(font
					(size 0.7874 0.5842)
					(thickness 0.1524)
				)
				(justify left)
			)
		)
		(property "Value" ""
			(at 0 0 90)
			(layer "F.Fab")
			(effects
				(font
					(size 1.27 1.27)
				)
			)
		)
		(duplicate_pad_numbers_are_jumpers no)
		(fp_line
			(start 3.800094 -5.249926)
			(end 3.800094 5.249926)
			(stroke
				(width 0.1524)
				(type default)
			)
			(layer "F.SilkS")
		)
		(fp_line
			(start 1.693926 -5.249926)
			(end 3.800094 -5.249926)
			(stroke
				(width 0.1524)
				(type default)
			)
			(layer "F.SilkS")
		)
		(fp_line
			(start -1.693926 -5.249926)
			(end 0 -4.064)
			(stroke
				(width 0.1524)
				(type default)
			)
			(layer "F.SilkS")
		)
		(fp_line
			(start -3.800094 -5.249926)
			(end -1.693926 -5.249926)
			(stroke
				(width 0.1524)
				(type default)
			)
			(layer "F.SilkS")
		)
		(fp_line
			(start 0 -4.064)
			(end 1.693926 -5.249926)
			(stroke
				(width 0.1524)
				(type default)
			)
			(layer "F.SilkS")
		)
		(fp_line
			(start 3.800094 5.249926)
			(end -3.800094 5.249926)
			(stroke
				(width 0.1524)
				(type default)
			)
			(layer "F.SilkS")
		)
		(fp_line
			(start -3.800094 5.249926)
			(end -3.800094 -5.249926)
			(stroke
				(width 0.1524)
				(type default)
			)
			(layer "F.SilkS")
		)
		(fp_poly
			(pts
				(xy -8.128254 -4.953254) (xy -8.128254 -3.937254) (xy -7.112254 -4.445254)
			)
			(stroke
				(width 0)
				(type default)
			)
			(fill yes)
			(layer "F.SilkS")
		)
		(fp_line
			(start 3.800094 -5.249926)
			(end -3.800094 -5.249926)
			(stroke
				(width 0.1)
				(type default)
			)
			(layer "F.Fab")
		)
		(fp_line
			(start -3.800094 -5.249926)
			(end -3.800094 5.249926)
			(stroke
				(width 0.1)
				(type default)
			)
			(layer "F.Fab")
		)
		(fp_line
			(start 3.800094 5.249926)
			(end 3.800094 -5.249926)
			(stroke
				(width 0.1)
				(type default)
			)
			(layer "F.Fab")
		)
		(fp_line
			(start -3.800094 5.249926)
			(end 3.800094 5.249926)
			(stroke
				(width 0.1)
				(type default)
			)
			(layer "F.Fab")
		)
		(fp_poly
			(pts
				(xy -7.2644 -4.953) (xy -7.2644 -3.937) (xy -6.2484 -4.445)
			)
			(stroke
				(width 0)
				(type default)
			)
			(fill yes)
			(layer "F.Fab")
		)
		(pad "1" smd rect
			(at -5.150104 -4.445)
			(size 0.4318 1.7018)
			(layers "F.Cu" "F.Mask" "F.Paste")
			(net "SPI_PCH_IO3_FLASH_R1")
		)
		(pad "2" smd rect
			(at -5.150104 -3.175)
			(size 0.4318 1.7018)
			(layers "F.Cu" "F.Mask" "F.Paste")
			(net "P3V3_AUX")
		)
		(pad "3" smd rect
			(at -5.150104 -1.905)
			(size 0.4318 1.7018)
			(layers "F.Cu" "F.Mask" "F.Paste")
			(net "RST_SPI_PCH_FLASH_R1_N")
		)
		(pad "4" smd rect
			(at -5.150104 -0.635)
			(size 0.4318 1.7018)
			(layers "F.Cu" "F.Mask" "F.Paste")
			(net "TP_J40_4")
		)
		(pad "5" smd rect
			(at -5.150104 0.635)
			(size 0.4318 1.7018)
			(layers "F.Cu" "F.Mask" "F.Paste")
			(net "TP_J40_5")
		)
		(pad "6" smd rect
			(at -5.150104 1.905)
			(size 0.4318 1.7018)
			(layers "F.Cu" "F.Mask" "F.Paste")
			(net "TP_J40_6")
		)
		(pad "7" smd rect
			(at -5.150104 3.175)
			(size 0.4318 1.7018)
			(layers "F.Cu" "F.Mask" "F.Paste")
			(net "SPI_PCH_CS0_FLASH_R1_N")
		)
		(pad "8" smd rect
			(at -5.150104 4.445)
			(size 0.4318 1.7018)
			(layers "F.Cu" "F.Mask" "F.Paste")
			(net "SPI_PCH_IO1_FLASH_R1")
		)
		(pad "9" smd rect
			(at 5.150104 4.445)
			(size 0.4318 1.7018)
			(layers "F.Cu" "F.Mask" "F.Paste")
			(net "SPI_PCH_IO2_FLASH_R1")
		)
		(pad "10" smd rect
			(at 5.150104 3.175)
			(size 0.4318 1.7018)
			(layers "F.Cu" "F.Mask" "F.Paste")
			(net "GND")
		)
		(pad "11" smd rect
			(at 5.150104 1.905)
			(size 0.4318 1.7018)
			(layers "F.Cu" "F.Mask" "F.Paste")
			(net "TP_J40_11")
		)
		(pad "12" smd rect
			(at 5.150104 0.635)
			(size 0.4318 1.7018)
			(layers "F.Cu" "F.Mask" "F.Paste")
			(net "TP_J40_12")
		)
		(pad "13" smd rect
			(at 5.150104 -0.635)
			(size 0.4318 1.7018)
			(layers "F.Cu" "F.Mask" "F.Paste")
			(net "TP_J40_13")
		)
		(pad "14" smd rect
			(at 5.150104 -1.905)
			(size 0.4318 1.7018)
			(layers "F.Cu" "F.Mask" "F.Paste")
			(net "TP_J40_14")
		)
		(pad "15" smd rect
			(at 5.150104 -3.175)
			(size 0.4318 1.7018)
			(layers "F.Cu" "F.Mask" "F.Paste")
			(net "SPI_PCH_IO0_FLASH_R1")
		)
		(pad "16" smd rect
			(at 5.150104 -4.445)
			(size 0.4318 1.7018)
			(layers "F.Cu" "F.Mask" "F.Paste")
			(net "SPI_PCH_CLK_FLASH_R1")
		)
	)
)
